(kicad_pcb
	(version 20240108)
	(generator "pcbnew")
	(generator_version "8.0")
	(general
		(thickness 1.62)
		(legacy_teardrops no)
	)
	(paper "A4")
	(title_block
		(title "Jetson Orin Baseboard")
		(date "2025-03-12")
		(rev "1.3.4")
		(company "Antmicro Ltd")
		(comment 1 "www.antmicro.com")
		(comment 9 "footprints 528-531 of 677")
	)
	(layers
		(0 "F.Cu" signal)
		(1 "In1.Cu" signal)
		(2 "In2.Cu" signal)
		(3 "In3.Cu" signal)
		(4 "In4.Cu" jumper)
		(5 "In5.Cu" signal)
		(6 "In6.Cu" signal)
		(31 "B.Cu" signal)
		(32 "B.Adhes" user "B.Adhesive")
		(33 "F.Adhes" user "F.Adhesive")
		(34 "B.Paste" user)
		(35 "F.Paste" user)
		(36 "B.SilkS" user "B.Silkscreen")
		(37 "F.SilkS" user "F.Silkscreen")
		(38 "B.Mask" user)
		(39 "F.Mask" user)
		(40 "Dwgs.User" user "User.Drawings")
		(41 "Cmts.User" user "User.Comments")
		(42 "Eco1.User" user "User.Eco1")
		(43 "Eco2.User" user "User.Eco2")
		(44 "Edge.Cuts" user)
		(45 "Margin" user)
		(46 "B.CrtYd" user "B.Courtyard")
		(47 "F.CrtYd" user "F.Courtyard")
		(48 "B.Fab" user)
		(49 "F.Fab" user)
	)
	(footprint "antmicro-footprints:R_0402_1005Metric"
		(layer "B.Cu")
		(at 134 116.55)
		(descr "Resistor SMD 0402")
		(tags "resistor SMD 0402")
		(property "Reference" "R8"
			(at -0.75 0.45 180)
			(layer "B.SilkS")
			(effects
				(font
					(size 0.7 0.7)
					(thickness 0.15)
				)
				(justify left bottom mirror)
			)
		)
		(property "Value" "R_4k7_0402"
			(at 0 -1.4 180)
			(layer "B.Fab")
			(effects
				(font
					(size 0.7 0.7)
					(thickness 0.15)
				)
				(justify left bottom mirror)
			)
		)
		(property "Footprint" "antmicro-footprints:R_0402_1005Metric"
			(at 0 0 0)
			(layer "F.Fab")
			(hide yes)
			(effects
				(font
					(size 1.27 1.27)
					(thickness 0.15)
				)
			)
		)
		(property "Datasheet" "https://www.bourns.com/docs/product-datasheets/cr.pdf"
			(at 0 0 0)
			(layer "F.Fab")
			(hide yes)
			(effects
				(font
					(size 1.27 1.27)
					(thickness 0.15)
				)
			)
		)
		(property "Author" "Antmicro"
			(at 0 0 0)
			(layer "B.Fab")
			(hide yes)
			(effects
				(font
					(size 1 1)
					(thickness 0.15)
				)
				(justify mirror)
			)
		)
		(property "License" "Apache-2.0"
			(at 0 0 0)
			(layer "B.Fab")
			(hide yes)
			(effects
				(font
					(size 1 1)
					(thickness 0.15)
				)
				(justify mirror)
			)
		)
		(property "MPN" "CR0402-FX-4701GLF"
			(at 0 0 0)
			(layer "B.Fab")
			(hide yes)
			(effects
				(font
					(size 1 1)
					(thickness 0.15)
				)
				(justify mirror)
			)
		)
		(property "Manufacturer" "Bourns"
			(at 0 0 0)
			(layer "B.Fab")
			(hide yes)
			(effects
				(font
					(size 1 1)
					(thickness 0.15)
				)
				(justify mirror)
			)
		)
		(property "Tolerance" "1%"
			(at 0 0 0)
			(layer "B.Fab")
			(hide yes)
			(effects
				(font
					(size 1 1)
					(thickness 0.15)
				)
				(justify mirror)
			)
		)
		(property "Val" "4k7"
			(at 0 0 0)
			(layer "B.Fab")
			(hide yes)
			(effects
				(font
					(size 1 1)
					(thickness 0.15)
				)
				(justify mirror)
			)
		)
		(sheetname "CSI")
		(sheetfile "csi.kicad_sch")
		(attr smd)
		(fp_rect
			(start -0.925 0.47)
			(end 0.925 -0.47)
			(stroke
				(width 0.05)
				(type default)
			)
			(fill none)
			(layer "B.CrtYd")
		)
		(fp_rect
			(start -0.5 0.25)
			(end 0.5 -0.25)
			(stroke
				(width 0.15)
				(type solid)
			)
			(fill none)
			(layer "B.Fab")
		)
		(fp_text user "License: Apache-2.0"
			(at -0.95 -5.169 180)
			(layer "B.Fab")
			(hide yes)
			(effects
				(font
					(size 0.7 0.7)
					(thickness 0.15)
				)
				(justify left bottom mirror)
			)
		)
		(fp_text user "${REFERENCE}"
			(at -0.95 -3.168 180)
			(layer "B.Fab")
			(hide yes)
			(effects
				(font
					(size 0.7 0.7)
					(thickness 0.15)
				)
				(justify left bottom mirror)
			)
		)
		(fp_text user "Author: Antmicro"
			(at -0.95 -4.169 180)
			(layer "B.Fab")
			(hide yes)
			(effects
				(font
					(size 0.7 0.7)
					(thickness 0.15)
				)
				(justify left bottom mirror)
			)
		)
		(pad "1" smd roundrect
			(at -0.48 0)
			(size 0.59 0.64)
			(layers "B.Cu" "B.Paste" "B.Mask")
			(roundrect_rratio 0.25)
			(net 1 "GND")
			(pintype "passive")
		)
		(pad "2" smd roundrect
			(at 0.48 0)
			(size 0.59 0.64)
			(layers "B.Cu" "B.Paste" "B.Mask")
			(roundrect_rratio 0.25)
			(net 335 "/CSI/CSIA_3V3_ISET")
			(pintype "passive")
		)
	)
	(footprint "antmicro-footprints:PCM12SMTR"
		(layer "B.Cu")
		(at 55.3895 72.796)
		(property "Reference" "SW1"
			(at 0.3705 2.474 180)
			(layer "B.SilkS")
			(effects
				(font
					(size 0.7 0.7)
					(thickness 0.15)
				)
				(justify left bottom mirror)
			)
		)
		(property "Value" "SW_SPDT_PCM12SMTR"
			(at 7.836 -5.94 180)
			(layer "B.Fab")
			(effects
				(font
					(size 0.7 0.7)
					(thickness 0.15)
				)
				(justify left bottom mirror)
			)
		)
		(property "Footprint" "antmicro-footprints:PCM12SMTR"
			(at 0 0 0)
			(layer "F.Fab")
			(hide yes)
			(effects
				(font
					(size 1.27 1.27)
					(thickness 0.15)
				)
			)
		)
		(property "Datasheet" "https://www.mouser.com/datasheet/2/60/pcm-1841544.pdf"
			(at 0 0 0)
			(layer "F.Fab")
			(hide yes)
			(effects
				(font
					(size 1.27 1.27)
					(thickness 0.15)
				)
			)
		)
		(property "Author" "Antmicro"
			(at 0 0 0)
			(layer "B.Fab")
			(hide yes)
			(effects
				(font
					(size 1 1)
					(thickness 0.15)
				)
				(justify mirror)
			)
		)
		(property "License" "Apache-2.0"
			(at 0 0 0)
			(layer "B.Fab")
			(hide yes)
			(effects
				(font
					(size 1 1)
					(thickness 0.15)
				)
				(justify mirror)
			)
		)
		(property "MPN" "PCM12SMTR"
			(at 0 0 0)
			(layer "B.Fab")
			(hide yes)
			(effects
				(font
					(size 1 1)
					(thickness 0.15)
				)
				(justify mirror)
			)
		)
		(property "Manufacturer" "C&K"
			(at 0 0 0)
			(layer "B.Fab")
			(hide yes)
			(effects
				(font
					(size 1 1)
					(thickness 0.15)
				)
				(justify mirror)
			)
		)
		(sheetname "Supply")
		(sheetfile "supply.kicad_sch")
		(attr smd)
		(fp_line
			(start -3.351 0.251)
			(end -3.351 -0.348)
			(stroke
				(width 0.15)
				(type solid)
			)
			(layer "B.SilkS")
		)
		(fp_line
			(start 0.1 1.251)
			(end -1.601 1.251)
			(stroke
				(width 0.15)
				(type solid)
			)
			(layer "B.SilkS")
		)
		(fp_line
			(start 2.9 -1.348)
			(end -2.901 -1.348)
			(stroke
				(width 0.15)
				(type solid)
			)
			(layer "B.SilkS")
		)
		(fp_line
			(start 3.349 -0.348)
			(end 3.349 0.251)
			(stroke
				(width 0.15)
				(type solid)
			)
			(layer "B.SilkS")
		)
		(fp_circle
			(center -3.15 2.45)
			(end -3.1 2.39)
			(stroke
				(width 0.15)
				(type solid)
			)
			(fill solid)
			(layer "B.SilkS")
		)
		(fp_line
			(start -4.42 -1.65)
			(end -1.77 -1.65)
			(stroke
				(width 0.05)
				(type solid)
			)
			(layer "B.CrtYd")
		)
		(fp_line
			(start -4.42 1.57)
			(end -4.42 -1.65)
			(stroke
				(width 0.05)
				(type solid)
			)
			(layer "B.CrtYd")
		)
		(fp_line
			(start -2.86 1.57)
			(end -4.42 1.57)
			(stroke
				(width 0.05)
				(type solid)
			)
			(layer "B.CrtYd")
		)
		(fp_line
			(start -2.86 2.7)
			(end -2.86 1.57)
			(stroke
				(width 0.05)
				(type solid)
			)
			(layer "B.CrtYd")
		)
		(fp_line
			(start -1.77 -3.08)
			(end 1.74 -3.08)
			(stroke
				(width 0.05)
				(type solid)
			)
			(layer "B.CrtYd")
		)
		(fp_line
			(start -1.77 -1.65)
			(end -1.77 -3.08)
			(stroke
				(width 0.05)
				(type solid)
			)
			(layer "B.CrtYd")
		)
		(fp_line
			(start 1.74 -3.08)
			(end 1.74 -1.65)
			(stroke
				(width 0.05)
				(type solid)
			)
			(layer "B.CrtYd")
		)
		(fp_line
			(start 1.74 -1.65)
			(end 4.4 -1.65)
			(stroke
				(width 0.05)
				(type solid)
			)
			(layer "B.CrtYd")
		)
		(fp_line
			(start 2.83 1.57)
			(end 2.83 2.7)
			(stroke
				(width 0.05)
				(type solid)
			)
			(layer "B.CrtYd")
		)
		(fp_line
			(start 2.83 2.7)
			(end -2.86 2.7)
			(stroke
				(width 0.05)
				(type solid)
			)
			(layer "B.CrtYd")
		)
		(fp_line
			(start 4.4 -1.65)
			(end 4.4 1.57)
			(stroke
				(width 0.05)
				(type solid)
			)
			(layer "B.CrtYd")
		)
		(fp_line
			(start 4.4 1.57)
			(end 2.83 1.57)
			(stroke
				(width 0.05)
				(type solid)
			)
			(layer "B.CrtYd")
		)
		(fp_line
			(start -3.351 -1.348)
			(end -1.502 -1.348)
			(stroke
				(width 0.15)
				(type solid)
			)
			(layer "B.Fab")
		)
		(fp_line
			(start -3.351 1.251)
			(end -3.351 -1.348)
			(stroke
				(width 0.15)
				(type solid)
			)
			(layer "B.Fab")
		)
		(fp_line
			(start -1.502 -2.849)
			(end -1.502 -1.348)
			(stroke
				(width 0.15)
				(type solid)
			)
			(layer "B.Fab")
		)
		(fp_line
			(start -1.502 -1.348)
			(end 1.499 -1.348)
			(stroke
				(width 0.15)
				(type solid)
			)
			(layer "B.Fab")
		)
		(fp_line
			(start 1.499 -2.849)
			(end -1.502 -2.849)
			(stroke
				(width 0.15)
				(type solid)
			)
			(layer "B.Fab")
		)
		(fp_line
			(start 1.499 -1.348)
			(end 1.499 -2.849)
			(stroke
				(width 0.15)
				(type solid)
			)
			(layer "B.Fab")
		)
		(fp_line
			(start 1.499 -1.348)
			(end 3.349 -1.348)
			(stroke
				(width 0.15)
				(type solid)
			)
			(layer "B.Fab")
		)
		(fp_line
			(start 3.349 -1.348)
			(end 3.349 1.251)
			(stroke
				(width 0.15)
				(type solid)
			)
			(layer "B.Fab")
		)
		(fp_line
			(start 3.349 1.251)
			(end -3.351 1.251)
			(stroke
				(width 0.15)
				(type solid)
			)
			(layer "B.Fab")
		)
		(fp_text user "${REFERENCE}"
			(at -2.152 -7.94 180)
			(layer "B.Fab")
			(hide yes)
			(effects
				(font
					(size 0.7 0.7)
					(thickness 0.15)
				)
				(justify left bottom mirror)
			)
		)
		(fp_text user "Author: Antmicro"
			(at -2.152 -9.14 180)
			(layer "B.Fab")
			(hide yes)
			(effects
				(font
					(size 0.7 0.7)
					(thickness 0.15)
				)
				(justify left bottom mirror)
			)
		)
		(fp_text user "License: Apache-2.0"
			(at -2.152 -10.339 180)
			(layer "B.Fab")
			(hide yes)
			(effects
				(font
					(size 0.7 0.7)
					(thickness 0.15)
				)
				(justify left bottom mirror)
			)
		)
		(pad "" np_thru_hole circle
			(at -1.502 -0.049)
			(size 0.9 0.9)
			(drill 0.9)
			(layers "*.Cu" "*.Mask")
		)
		(pad "" np_thru_hole circle
			(at 1.499 -0.049)
			(size 0.9 0.9)
			(drill 0.9)
			(layers "*.Cu" "*.Mask")
		)
		(pad "1" smd roundrect
			(at -2.25 1.7)
			(size 0.7 1.5)
			(layers "B.Cu" "B.Paste" "B.Mask")
			(roundrect_rratio 0.25)
			(net 534 "unconnected-(SW1-Pad1)")
			(pintype "passive+no_connect")
		)
		(pad "2" smd roundrect
			(at 0.749 1.7)
			(size 0.7 1.5)
			(layers "B.Cu" "B.Paste" "B.Mask")
			(roundrect_rratio 0.25)
			(net 530 "Net-(R256-Pad1)")
			(pintype "passive")
		)
		(pad "3" smd roundrect
			(at 2.248 1.7)
			(size 0.7 1.5)
			(layers "B.Cu" "B.Paste" "B.Mask")
			(roundrect_rratio 0.25)
			(net 137 "Net-(D36-A)")
			(pintype "passive")
		)
		(pad "S1" smd roundrect
			(at -3.651 0.915)
			(size 1 0.8)
			(layers "B.Cu" "B.Paste" "B.Mask")
			(roundrect_rratio 0.25)
			(net 1 "GND")
			(pinfunction "SH")
			(pintype "passive")
		)
		(pad "S2" smd roundrect
			(at -3.651 -1.013)
			(size 1 0.8)
			(layers "B.Cu" "B.Paste" "B.Mask")
			(roundrect_rratio 0.25)
			(net 1 "GND")
			(pinfunction "SH")
			(pintype "passive")
		)
		(pad "S3" smd roundrect
			(at 3.65 -1.013)
			(size 1 0.8)
			(layers "B.Cu" "B.Paste" "B.Mask")
			(roundrect_rratio 0.25)
			(net 1 "GND")
			(pinfunction "SH")
			(pintype "passive")
		)
		(pad "S4" smd roundrect
			(at 3.65 0.915)
			(size 1 0.8)
			(layers "B.Cu" "B.Paste" "B.Mask")
			(roundrect_rratio 0.25)
			(net 1 "GND")
			(pinfunction "SH")
			(pintype "passive")
		)
	)
	(footprint "antmicro-footprints:C_0402_1005Metric"
		(layer "B.Cu")
		(at 69.475 86.3 90)
		(descr "Capacitor SMD 0402")
		(tags "capacitor SMD 0402")
		(property "Reference" "C101"
			(at 1.4 1.335 -90)
			(layer "B.SilkS")
			(effects
				(font
					(size 0.7 0.7)
					(thickness 0.15)
				)
				(justify left bottom mirror)
			)
		)
		(property "Value" "C_100n_0402"
			(at 0 -1.4 -90)
			(layer "B.Fab")
			(effects
				(font
					(size 0.7 0.7)
					(thickness 0.15)
				)
				(justify left bottom mirror)
			)
		)
		(property "Footprint" "antmicro-footprints:C_0402_1005Metric"
			(at 0 0 90)
			(layer "F.Fab")
			(hide yes)
			(effects
				(font
					(size 1.27 1.27)
					(thickness 0.15)
				)
			)
		)
		(property "Datasheet" "https://www.murata.com/products/productdetail?partno=GRM155R61H104KE14%23"
			(at 0 0 90)
			(layer "F.Fab")
			(hide yes)
			(effects
				(font
					(size 1.27 1.27)
					(thickness 0.15)
				)
			)
		)
		(property "Author" "Antmicro"
			(at 155.775 16.825 0)
			(layer "B.Fab")
			(hide yes)
			(effects
				(font
					(size 1 1)
					(thickness 0.15)
				)
				(justify mirror)
			)
		)
		(property "Dielectric" "X5R"
			(at 155.775 16.825 0)
			(layer "B.Fab")
			(hide yes)
			(effects
				(font
					(size 1 1)
					(thickness 0.15)
				)
				(justify mirror)
			)
		)
		(property "License" "Apache-2.0"
			(at 155.775 16.825 0)
			(layer "B.Fab")
			(hide yes)
			(effects
				(font
					(size 1 1)
					(thickness 0.15)
				)
				(justify mirror)
			)
		)
		(property "MPN" "GRM155R61H104KE14D"
			(at 155.775 16.825 0)
			(layer "B.Fab")
			(hide yes)
			(effects
				(font
					(size 1 1)
					(thickness 0.15)
				)
				(justify mirror)
			)
		)
		(property "Manufacturer" "Murata"
			(at 155.775 16.825 0)
			(layer "B.Fab")
			(hide yes)
			(effects
				(font
					(size 1 1)
					(thickness 0.15)
				)
				(justify mirror)
			)
		)
		(property "Val" "100n"
			(at 155.775 16.825 0)
			(layer "B.Fab")
			(hide yes)
			(effects
				(font
					(size 1 1)
					(thickness 0.15)
				)
				(justify mirror)
			)
		)
		(property "Voltage" "50V"
			(at 155.775 16.825 0)
			(layer "B.Fab")
			(hide yes)
			(effects
				(font
					(size 1 1)
					(thickness 0.15)
				)
				(justify mirror)
			)
		)
		(sheetname "CSI")
		(sheetfile "csi.kicad_sch")
		(attr smd)
		(fp_rect
			(start -0.925 0.47)
			(end 0.925 -0.47)
			(stroke
				(width 0.05)
				(type default)
			)
			(fill none)
			(layer "B.CrtYd")
		)
		(fp_line
			(start 0.504 -0.248)
			(end 0.504 0.25)
			(stroke
				(width 0.15)
				(type solid)
			)
			(layer "B.Fab")
		)
		(fp_line
			(start -0.494 -0.248)
			(end 0.504 -0.248)
			(stroke
				(width 0.15)
				(type solid)
			)
			(layer "B.Fab")
		)
		(fp_line
			(start 0.504 0.25)
			(end -0.494 0.25)
			(stroke
				(width 0.15)
				(type solid)
			)
			(layer "B.Fab")
		)
		(fp_line
			(start -0.494 0.25)
			(end -0.494 -0.248)
			(stroke
				(width 0.15)
				(type solid)
			)
			(layer "B.Fab")
		)
		(fp_text user "${REFERENCE}"
			(at -0.932 -3.168 -90)
			(layer "B.Fab")
			(hide yes)
			(effects
				(font
					(size 0.7 0.7)
					(thickness 0.15)
				)
				(justify left bottom mirror)
			)
		)
		(fp_text user "License: Apache-2.0"
			(at -0.932 -5.17 -90)
			(layer "B.Fab")
			(hide yes)
			(effects
				(font
					(size 0.7 0.7)
					(thickness 0.15)
				)
				(justify left bottom mirror)
			)
		)
		(fp_text user "Author: Antmicro"
			(at -0.932 -4.17 -90)
			(layer "B.Fab")
			(hide yes)
			(effects
				(font
					(size 0.7 0.7)
					(thickness 0.15)
				)
				(justify left bottom mirror)
			)
		)
		(pad "1" smd roundrect
			(at -0.48 0 90)
			(size 0.59 0.64)
			(layers "B.Cu" "B.Paste" "B.Mask")
			(roundrect_rratio 0.25)
			(net 1 "GND")
			(pintype "passive")
		)
		(pad "2" smd roundrect
			(at 0.48 0 90)
			(size 0.59 0.64)
			(layers "B.Cu" "B.Paste" "B.Mask")
			(roundrect_rratio 0.25)
			(net 87 "+3V3")
			(pintype "passive")
		)
	)
	(footprint "antmicro-footprints:TP_SMD_0.75mm"
		(layer "B.Cu")
		(at 68 95.9)
		(property "Reference" "TP19"
			(at 5.53 0.21 -90)
			(layer "B.SilkS")
			(hide yes)
			(effects
				(font
					(size 0.7 0.7)
					(thickness 0.15)
				)
				(justify left bottom mirror)
			)
		)
		(property "Value" "TP_0.75mm_SMD"
			(at 0 -1.2 180)
			(layer "B.Fab")
			(effects
				(font
					(size 0.7 0.7)
					(thickness 0.15)
				)
				(justify left bottom mirror)
			)
		)
		(property "Footprint" "antmicro-footprints:TP_SMD_0.75mm"
			(at 0 0 0)
			(layer "F.Fab")
			(hide yes)
			(effects
				(font
					(size 1.27 1.27)
					(thickness 0.15)
				)
			)
		)
		(property "Author" "Antmicro"
			(at 0 0 0)
			(layer "B.Fab")
			(hide yes)
			(effects
				(font
					(size 1 1)
					(thickness 0.15)
				)
				(justify mirror)
			)
		)
		(property "License" "Apache-2.0"
			(at 0 0 0)
			(layer "B.Fab")
			(hide yes)
			(effects
				(font
					(size 1 1)
					(thickness 0.15)
				)
				(justify mirror)
			)
		)
		(property "MPN" ""
			(at 0 0 0)
			(layer "B.Fab")
			(hide yes)
			(effects
				(font
					(size 1 1)
					(thickness 0.15)
				)
				(justify mirror)
			)
		)
		(property "Manufacturer" ""
			(at 0 0 0)
			(layer "B.Fab")
			(hide yes)
			(effects
				(font
					(size 1 1)
					(thickness 0.15)
				)
				(justify mirror)
			)
		)
		(sheetname "USB Debug, DP")
		(sheetfile "usb.kicad_sch")
		(attr exclude_from_pos_files exclude_from_bom)
		(fp_circle
			(center 0 0)
			(end 0.475 0)
			(stroke
				(width 0.05)
				(type default)
			)
			(fill none)
			(layer "B.CrtYd")
		)
		(fp_text user "${REFERENCE}"
			(at -0.4 -2.7 180)
			(layer "B.Fab")
			(hide yes)
			(effects
				(font
					(size 0.7 0.7)
					(thickness 0.15)
				)
				(justify left bottom mirror)
			)
		)
		(fp_text user "License: Apache-2.0"
			(at -0.4 -5.101 180)
			(layer "B.Fab")
			(hide yes)
			(effects
				(font
					(size 0.7 0.7)
					(thickness 0.15)
				)
				(justify left bottom mirror)
			)
		)
		(fp_text user "Author: Antmicro"
			(at -0.4 -3.901 180)
			(layer "B.Fab")
			(hide yes)
			(effects
				(font
					(size 0.7 0.7)
					(thickness 0.15)
				)
				(justify left bottom mirror)
			)
		)
		(pad "1" smd circle
			(at 0 0)
			(size 0.75 0.75)
			(layers "B.Cu" "B.Mask")
			(net 395 "/USB Debug, DP/PDC_I2C2_SCL")
			(pinfunction "1")
			(pintype "passive")
		)
	)
)
